#ISCELL
  mstr_misc dns *
  *
#ISCELL
  mstr_symbols design_note *
  *
#ISCELL
  mstr_symbols intel_corp_bpage *
  *
#ISCELL
  mstr_standard offpage *
  page226_i1
#ISCELL
  mstr_standard offpage *
  page226_i10
#ISCELL
  mstr_standard offpage *
  page226_i11
#CELL
  mstr_discrete cap *
  page226_i12
#CELL
  mstr_discrete res *
  page226_i13
#CELL
  mstr_discrete res *
  page226_i14
#CELL
  w_hdl sc22p50v2jn-4gp *
  page226_i15
#CELL
  mstr_discrete res *
  page226_i16
#CELL
  w_hdl sc22p50v2jn-4gp *
  page226_i17
#CELL
  mstr_discrete res *
  page226_i18
#CELL
  mstr_discrete res *
  page226_i19
#ISCELL
  mstr_standard offpage *
  page226_i2
#ISCELL
  mstr_symbols pvccio_cpu1 *
  page226_i21
#ISCELL
  mstr_symbols gnd *
  page226_i22
#CELL
  mstr_discrete cap *
  page226_i23
#ISCELL
  mstr_symbols gnd *
  page226_i24
#ISCELL
  mstr_symbols gnd *
  page226_i25
#ISCELL
  mstr_symbols gnd *
  page226_i26
#ISCELL
  mstr_symbols gnd *
  page226_i28
#ISCELL
  mstr_symbols gnd *
  page226_i29
#ISCELL
  mstr_standard offpage *
  page226_i3
#ISCELL
  mstr_symbols gnd *
  page226_i31
#CELL
  dev_discrete cap_a *
  page226_i32
#ISCELL
  mstr_symbols gnd *
  page226_i33
#CELL
  mstr_discrete res *
  page226_i34
#ISCELL
  mstr_symbols p3v3_stby *
  page226_i35
#CELL
  mstr_discrete res *
  page226_i36
#ISCELL
  mstr_symbols gnd *
  page226_i37
#CELL
  dev_discrete cap_a *
  page226_i38
#ISCELL
  mstr_symbols gnd *
  page226_i39
#ISCELL
  mstr_standard offpage *
  page226_i4
#CELL
  mstr_discrete cap *
  page226_i40
#CELL
  mstr_discrete res *
  page226_i41
#CELL
  dev_discrete cap_a *
  page226_i44
#CELL
  dev_discrete cap_a *
  page226_i45
#CELL
  mstr_discrete res *
  page226_i46
#CELL
  mstr_discrete res *
  page226_i48
#CELL
  mstr_discrete res *
  page226_i49
#ISCELL
  mstr_standard offpage *
  page226_i5
#CELL
  mstr_discrete res *
  page226_i50
#ISCELL
  mstr_standard offpage *
  page226_i51
#ISCELL
  mstr_symbols p3v3_stby *
  page226_i52
#CELL
  mstr_discrete res *
  page226_i53
#CELL
  mstr_discrete res *
  page226_i54
#CELL
  mstr_discrete res *
  page226_i55
#CELL
  mstr_discrete res *
  page226_i57
#ISCELL
  mstr_symbols pvccio_cpu1 *
  page226_i58
#ISCELL
  mstr_standard offpage *
  page226_i59
#ISCELL
  mstr_standard offpage *
  page226_i6
#ISCELL
  mstr_standard offpage *
  page226_i60
#ISCELL
  mstr_standard offpage *
  page226_i61
#ISCELL
  mstr_standard offpage *
  page226_i62
#ISCELL
  mstr_standard offpage *
  page226_i63
#ISCELL
  mstr_standard offpage *
  page226_i64
#ISCELL
  mstr_standard offpage *
  page226_i65
#ISCELL
  mstr_standard offpage *
  page226_i66
#ISCELL
  mstr_standard offpage *
  page226_i67
#ISCELL
  mstr_standard offpage *
  page226_i68
#CELL
  mstr_controller pxm1310b *
  page226_i69
#ISCELL
  mstr_standard offpage *
  page226_i7
#CELL
  mstr_discrete res *
  page226_i70
#CELL
  mstr_discrete res *
  page226_i72
#CELL
  mstr_discrete res *
  page226_i73
#CELL
  mstr_discrete res *
  page226_i74
#CELL
  mstr_discrete res *
  page226_i75
#ISCELL
  mstr_standard offpage *
  page226_i8
#ISCELL
  mstr_standard offpage *
  page226_i9
